(kicad_pcb
	(version 20260206)
	(generator "pcbnew")
	(generator_version "10.0")
	(general
		(thickness 1.6)
		(legacy_teardrops no)
	)
	(paper "A4")
	(title_block
		(title "baseboard — 13948-1b.1110WZS1818.brd")
		(comment 1 "Honey Badger (Wiwynn) / footprints 117-124 of 2523")
	)
	(layers
		(0 "F.Cu" signal "TOP")
		(4 "In1.Cu" signal "L2GND")
		(6 "In2.Cu" signal "L3")
		(8 "In3.Cu" signal "L4VCC")
		(10 "In4.Cu" signal "L5VCC")
		(12 "In5.Cu" signal "L6")
		(14 "In6.Cu" signal "L7GND")
		(2 "B.Cu" signal "BOTTOM")
		(9 "F.Adhes" user "F.Adhesive")
		(11 "B.Adhes" user "B.Adhesive")
		(13 "F.Paste" user "Package Geometry/Pastemask Top")
		(15 "B.Paste" user "Package Geometry/Pastemask Bottom")
		(5 "F.SilkS" user "Ref Des/Silkscreen Top")
		(7 "B.SilkS" user "Ref Des/Silkscreen Bottom")
		(1 "F.Mask" user "Board Geometry/Soldermask Top")
		(3 "B.Mask" user "Board Geometry/Soldermask Bottom")
		(17 "Dwgs.User" user "User.Drawings")
		(19 "Cmts.User" user "User.Comments")
		(21 "Eco1.User" user "User.Eco1")
		(23 "Eco2.User" user "User.Eco2")
		(25 "Edge.Cuts" user "Board Geometry/Outline")
		(27 "Margin" user)
		(31 "F.CrtYd" user "Package Geometry/Place Bound Top")
		(29 "B.CrtYd" user "Package Geometry/Place Bound Bottom")
		(35 "F.Fab" user "Ref Des/Assembly Top")
		(33 "B.Fab" user "Ref Des/Assembly Bottom")
	)
	(footprint ""
		(layer "F.Cu")
		(at 117.74297 -114.3 180)
		(property "Reference" "SC1072"
			(at 0 0 180)
			(layer "F.SilkS")
			(hide yes)
			(effects
				(font
					(size 1.27 1.27)
				)
			)
		)
		(property "Value" "SCD01U10V1KX-GP"
			(at -2.8321 -1.7399 180)
			(unlocked yes)
			(layer "F.Fab")
			(hide yes)
			(effects
				(font
					(size 1.016 1.016)
					(thickness 0.1524)
				)
			)
		)
		(property "Device Type" "C0201H13"
			(at -2.8321 -3.2639 180)
			(unlocked yes)
			(layer "F.Fab")
			(hide yes)
			(effects
				(font
					(size 1.016 1.016)
					(thickness 0.1524)
				)
			)
		)
		(duplicate_pad_numbers_are_jumpers no)
		(fp_rect
			(start -0.2794 0.6477)
			(end 0.2794 -0.6477)
			(stroke
				(width 0)
				(type default)
			)
			(fill no)
			(layer "F.CrtYd")
		)
		(fp_rect
			(start -0.2794 0.6477)
			(end 0.2794 -0.6477)
			(stroke
				(width 0)
				(type default)
			)
			(fill no)
			(layer "F.Fab")
		)
		(pad "1" smd custom
			(at 0 -0.2794 180)
			(size 0.0762 0.0762)
			(layers "F.Cu" "F.Mask" "F.Paste")
			(net "SAS_HDD_TX2_N")
			(options
				(clearance outline)
				(anchor circle)
			)
			(primitives
				(gr_poly
					(pts
						(arc
							(start 0.1524 -0.127)
							(mid 0.137521 -0.162921)
							(end 0.1016 -0.1778)
						)
						(arc
							(start -0.1016 -0.1778)
							(mid -0.137521 -0.162921)
							(end -0.1524 -0.127)
						)
						(arc
							(start -0.1524 0.127)
							(mid -0.137521 0.162921)
							(end -0.1016 0.1778)
						)
						(arc
							(start 0.1016 0.1778)
							(mid 0.137521 0.162921)
							(end 0.1524 0.127)
						)
					)
					(width 0)
					(fill yes)
				)
			)
		)
		(pad "2" smd custom
			(at 0 0.2794 180)
			(size 0.0762 0.0762)
			(layers "F.Cu" "F.Mask" "F.Paste")
			(net "SAS_EXP_GF_TX_DN6")
			(options
				(clearance outline)
				(anchor circle)
			)
			(primitives
				(gr_poly
					(pts
						(arc
							(start 0.1524 -0.127)
							(mid 0.137521 -0.162921)
							(end 0.1016 -0.1778)
						)
						(arc
							(start -0.1016 -0.1778)
							(mid -0.137521 -0.162921)
							(end -0.1524 -0.127)
						)
						(arc
							(start -0.1524 0.127)
							(mid -0.137521 0.162921)
							(end -0.1016 0.1778)
						)
						(arc
							(start 0.1016 0.1778)
							(mid 0.137521 0.162921)
							(end 0.1524 0.127)
						)
					)
					(width 0)
					(fill yes)
				)
			)
		)
	)
	(footprint ""
		(layer "F.Cu")
		(at 83.439 -24.384 180)
		(property "Reference" "PC221"
			(at 0 0 180)
			(layer "F.SilkS")
			(hide yes)
			(effects
				(font
					(size 1.27 1.27)
				)
			)
		)
		(property "Value" "SC1KP50V2KX-1GP"
			(at 1.1811 -2.7051 180)
			(unlocked yes)
			(layer "F.Fab")
			(hide yes)
			(effects
				(font
					(size 1.016 1.016)
					(thickness 0.1524)
				)
			)
		)
		(property "Device Type" "C402H22"
			(at 1.1811 -4.2291 180)
			(unlocked yes)
			(layer "F.Fab")
			(hide yes)
			(effects
				(font
					(size 1.016 1.016)
					(thickness 0.1524)
				)
			)
		)
		(duplicate_pad_numbers_are_jumpers no)
		(fp_rect
			(start -0.4318 0.9525)
			(end 0.4318 -0.9525)
			(stroke
				(width 0)
				(type default)
			)
			(fill no)
			(layer "F.CrtYd")
		)
		(fp_rect
			(start -0.4318 0.9525)
			(end 0.4318 -0.9525)
			(stroke
				(width 0)
				(type default)
			)
			(fill no)
			(layer "F.Fab")
		)
		(pad "1" smd custom
			(at 0 -0.4445 180)
			(size 0.1524 0.1524)
			(layers "F.Cu" "F.Mask" "F.Paste")
			(net "VT235_VREF")
			(options
				(clearance outline)
				(anchor circle)
			)
			(primitives
				(gr_poly
					(pts
						(arc
							(start 0.3048 -0.2032)
							(mid 0.275042 -0.275042)
							(end 0.2032 -0.3048)
						)
						(arc
							(start -0.2032 -0.3048)
							(mid -0.275042 -0.275042)
							(end -0.3048 -0.2032)
						)
						(arc
							(start -0.3048 0.2032)
							(mid -0.275042 0.275042)
							(end -0.2032 0.3048)
						)
						(arc
							(start 0.2032 0.3048)
							(mid 0.275042 0.275042)
							(end 0.3048 0.2032)
						)
					)
					(width 0)
					(fill yes)
				)
			)
		)
		(pad "2" smd custom
			(at 0 0.4445 180)
			(size 0.1524 0.1524)
			(layers "F.Cu" "F.Mask" "F.Paste")
			(net "VT235_VDES_RCC")
			(options
				(clearance outline)
				(anchor circle)
			)
			(primitives
				(gr_poly
					(pts
						(arc
							(start 0.3048 -0.2032)
							(mid 0.275042 -0.275042)
							(end 0.2032 -0.3048)
						)
						(arc
							(start -0.2032 -0.3048)
							(mid -0.275042 -0.275042)
							(end -0.3048 -0.2032)
						)
						(arc
							(start -0.3048 0.2032)
							(mid -0.275042 0.275042)
							(end -0.2032 0.3048)
						)
						(arc
							(start 0.2032 0.3048)
							(mid 0.275042 0.275042)
							(end 0.3048 0.2032)
						)
					)
					(width 0)
					(fill yes)
				)
			)
		)
	)
	(footprint ""
		(layer "F.Cu")
		(at 182.934864 -22.551136 180)
		(property "Reference" "R384"
			(at 0 0 180)
			(layer "F.SilkS")
			(hide yes)
			(effects
				(font
					(size 1.27 1.27)
				)
			)
		)
		(property "Value" "4K75R2F-1-GP"
			(at 0.064008 -3.993896 180)
			(unlocked yes)
			(layer "F.Fab")
			(hide yes)
			(effects
				(font
					(size 1.016 1.016)
					(thickness 0.1524)
				)
			)
		)
		(property "Device Type" "R402H16"
			(at 0.064008 -5.517896 180)
			(unlocked yes)
			(layer "F.Fab")
			(hide yes)
			(effects
				(font
					(size 1.016 1.016)
					(thickness 0.1524)
				)
			)
		)
		(duplicate_pad_numbers_are_jumpers no)
		(fp_line
			(start 0.508 -0.9398)
			(end -0.508 -0.9398)
			(stroke
				(width 0.1524)
				(type default)
			)
			(layer "F.SilkS")
		)
		(fp_line
			(start -0.508 -0.9398)
			(end -0.508 0.9398)
			(stroke
				(width 0.1524)
				(type default)
			)
			(layer "F.SilkS")
		)
		(fp_rect
			(start -0.508 0.9398)
			(end 0.508 -0.9398)
			(stroke
				(width 0)
				(type default)
			)
			(fill no)
			(layer "F.CrtYd")
		)
		(fp_rect
			(start -0.508 0.9398)
			(end 0.508 -0.9398)
			(stroke
				(width 0)
				(type default)
			)
			(fill no)
			(layer "F.Fab")
		)
		(pad "1" smd custom
			(at 0 -0.4445 180)
			(size 0.1397 0.1397)
			(layers "F.Cu" "F.Mask" "F.Paste")
			(net "P3V3_STBY")
			(options
				(clearance outline)
				(anchor circle)
			)
			(primitives
				(gr_poly
					(pts
						(arc
							(start -0.1778 -0.2794)
							(mid -0.249642 -0.249642)
							(end -0.2794 -0.1778)
						)
						(arc
							(start -0.2794 0.1778)
							(mid -0.249642 0.249642)
							(end -0.1778 0.2794)
						)
						(arc
							(start 0.1778 0.2794)
							(mid 0.249642 0.249642)
							(end 0.2794 0.1778)
						)
						(arc
							(start 0.2794 -0.1778)
							(mid 0.249642 -0.249642)
							(end 0.1778 -0.2794)
						)
					)
					(width 0)
					(fill yes)
				)
			)
		)
		(pad "2" smd custom
			(at 0 0.4445 180)
			(size 0.1397 0.1397)
			(layers "F.Cu" "F.Mask" "F.Paste")
			(net "PHY_FDX")
			(options
				(clearance outline)
				(anchor circle)
			)
			(primitives
				(gr_poly
					(pts
						(arc
							(start -0.1778 -0.2794)
							(mid -0.249642 -0.249642)
							(end -0.2794 -0.1778)
						)
						(arc
							(start -0.2794 0.1778)
							(mid -0.249642 0.249642)
							(end -0.1778 0.2794)
						)
						(arc
							(start 0.1778 0.2794)
							(mid 0.249642 0.249642)
							(end 0.2794 0.1778)
						)
						(arc
							(start 0.2794 -0.1778)
							(mid 0.249642 -0.249642)
							(end 0.1778 -0.2794)
						)
					)
					(width 0)
					(fill yes)
				)
			)
		)
	)
	(footprint ""
		(layer "F.Cu")
		(at 318.893952 -59.69 90)
		(property "Reference" "R214"
			(at 0 0 90)
			(layer "F.SilkS")
			(hide yes)
			(effects
				(font
					(size 1.27 1.27)
				)
			)
		)
		(property "Value" "0R2J-2-GP"
			(at 0.064008 -3.993896 90)
			(unlocked yes)
			(layer "F.Fab")
			(hide yes)
			(effects
				(font
					(size 1.016 1.016)
					(thickness 0.1524)
				)
			)
		)
		(property "Device Type" "R402H16"
			(at 0.064008 -5.517896 90)
			(unlocked yes)
			(layer "F.Fab")
			(hide yes)
			(effects
				(font
					(size 1.016 1.016)
					(thickness 0.1524)
				)
			)
		)
		(duplicate_pad_numbers_are_jumpers no)
		(fp_line
			(start 0.508 -0.9398)
			(end -0.508 -0.9398)
			(stroke
				(width 0.1524)
				(type default)
			)
			(layer "F.SilkS")
		)
		(fp_line
			(start -0.508 -0.9398)
			(end -0.508 0.9398)
			(stroke
				(width 0.1524)
				(type default)
			)
			(layer "F.SilkS")
		)
		(fp_rect
			(start -0.508 0.9398)
			(end 0.508 -0.9398)
			(stroke
				(width 0)
				(type default)
			)
			(fill no)
			(layer "F.CrtYd")
		)
		(fp_rect
			(start -0.508 0.9398)
			(end 0.508 -0.9398)
			(stroke
				(width 0)
				(type default)
			)
			(fill no)
			(layer "F.Fab")
		)
		(pad "1" smd custom
			(at 0 -0.4445 90)
			(size 0.1397 0.1397)
			(layers "F.Cu" "F.Mask" "F.Paste")
			(net "PMU_PLTRST_N_10G")
			(options
				(clearance outline)
				(anchor circle)
			)
			(primitives
				(gr_poly
					(pts
						(arc
							(start -0.1778 -0.2794)
							(mid -0.249642 -0.249642)
							(end -0.2794 -0.1778)
						)
						(arc
							(start -0.2794 0.1778)
							(mid -0.249642 0.249642)
							(end -0.1778 0.2794)
						)
						(arc
							(start 0.1778 0.2794)
							(mid 0.249642 0.249642)
							(end 0.2794 0.1778)
						)
						(arc
							(start 0.2794 -0.1778)
							(mid 0.249642 -0.249642)
							(end 0.1778 -0.2794)
						)
					)
					(width 0)
					(fill yes)
				)
			)
		)
		(pad "2" smd custom
			(at 0 0.4445 90)
			(size 0.1397 0.1397)
			(layers "F.Cu" "F.Mask" "F.Paste")
			(net "PMU_PLTRST_N")
			(options
				(clearance outline)
				(anchor circle)
			)
			(primitives
				(gr_poly
					(pts
						(arc
							(start -0.1778 -0.2794)
							(mid -0.249642 -0.249642)
							(end -0.2794 -0.1778)
						)
						(arc
							(start -0.2794 0.1778)
							(mid -0.249642 0.249642)
							(end -0.1778 0.2794)
						)
						(arc
							(start 0.1778 0.2794)
							(mid 0.249642 0.249642)
							(end 0.2794 0.1778)
						)
						(arc
							(start 0.2794 -0.1778)
							(mid 0.249642 -0.249642)
							(end 0.1778 -0.2794)
						)
					)
					(width 0)
					(fill yes)
				)
			)
		)
	)
	(footprint ""
		(layer "F.Cu")
		(at 323.596 -143.383 -90)
		(property "Reference" "C306"
			(at 0 0 270)
			(layer "F.SilkS")
			(hide yes)
			(effects
				(font
					(size 1.27 1.27)
				)
			)
		)
		(property "Value" "SC15P50V2JN-2-GP"
			(at 1.1811 -2.7051 270)
			(unlocked yes)
			(layer "F.Fab")
			(hide yes)
			(effects
				(font
					(size 1.016 1.016)
					(thickness 0.1524)
				)
			)
		)
		(property "Device Type" "C402H22"
			(at 1.1811 -4.2291 270)
			(unlocked yes)
			(layer "F.Fab")
			(hide yes)
			(effects
				(font
					(size 1.016 1.016)
					(thickness 0.1524)
				)
			)
		)
		(duplicate_pad_numbers_are_jumpers no)
		(fp_rect
			(start -0.4318 0.9525)
			(end 0.4318 -0.9525)
			(stroke
				(width 0)
				(type default)
			)
			(fill no)
			(layer "F.CrtYd")
		)
		(fp_rect
			(start -0.4318 0.9525)
			(end 0.4318 -0.9525)
			(stroke
				(width 0)
				(type default)
			)
			(fill no)
			(layer "F.Fab")
		)
		(pad "1" smd custom
			(at 0 -0.4445 270)
			(size 0.1524 0.1524)
			(layers "F.Cu" "F.Mask" "F.Paste")
			(net "RTC_OSCI")
			(options
				(clearance outline)
				(anchor circle)
			)
			(primitives
				(gr_poly
					(pts
						(arc
							(start 0.3048 -0.2032)
							(mid 0.275042 -0.275042)
							(end 0.2032 -0.3048)
						)
						(arc
							(start -0.2032 -0.3048)
							(mid -0.275042 -0.275042)
							(end -0.3048 -0.2032)
						)
						(arc
							(start -0.3048 0.2032)
							(mid -0.275042 0.275042)
							(end -0.2032 0.3048)
						)
						(arc
							(start 0.2032 0.3048)
							(mid 0.275042 0.275042)
							(end 0.3048 0.2032)
						)
					)
					(width 0)
					(fill yes)
				)
			)
		)
		(pad "2" smd custom
			(at 0 0.4445 270)
			(size 0.1524 0.1524)
			(layers "F.Cu" "F.Mask" "F.Paste")
			(net "GND")
			(options
				(clearance outline)
				(anchor circle)
			)
			(primitives
				(gr_poly
					(pts
						(arc
							(start 0.3048 -0.2032)
							(mid 0.275042 -0.275042)
							(end 0.2032 -0.3048)
						)
						(arc
							(start -0.2032 -0.3048)
							(mid -0.275042 -0.275042)
							(end -0.3048 -0.2032)
						)
						(arc
							(start -0.3048 0.2032)
							(mid -0.275042 0.275042)
							(end -0.2032 0.3048)
						)
						(arc
							(start 0.2032 0.3048)
							(mid 0.275042 0.275042)
							(end 0.3048 0.2032)
						)
					)
					(width 0)
					(fill yes)
				)
			)
		)
	)
	(footprint ""
		(layer "F.Cu")
		(at 114.18697 -114.3 180)
		(property "Reference" "SC1076"
			(at 0 0 180)
			(layer "F.SilkS")
			(hide yes)
			(effects
				(font
					(size 1.27 1.27)
				)
			)
		)
		(property "Value" "SCD01U10V1KX-GP"
			(at -2.8321 -1.7399 180)
			(unlocked yes)
			(layer "F.Fab")
			(hide yes)
			(effects
				(font
					(size 1.016 1.016)
					(thickness 0.1524)
				)
			)
		)
		(property "Device Type" "C0201H13"
			(at -2.8321 -3.2639 180)
			(unlocked yes)
			(layer "F.Fab")
			(hide yes)
			(effects
				(font
					(size 1.016 1.016)
					(thickness 0.1524)
				)
			)
		)
		(duplicate_pad_numbers_are_jumpers no)
		(fp_rect
			(start -0.2794 0.6477)
			(end 0.2794 -0.6477)
			(stroke
				(width 0)
				(type default)
			)
			(fill no)
			(layer "F.CrtYd")
		)
		(fp_rect
			(start -0.2794 0.6477)
			(end 0.2794 -0.6477)
			(stroke
				(width 0)
				(type default)
			)
			(fill no)
			(layer "F.Fab")
		)
		(pad "1" smd custom
			(at 0 -0.2794 180)
			(size 0.0762 0.0762)
			(layers "F.Cu" "F.Mask" "F.Paste")
			(net "SAS_HDD_TX4_N")
			(options
				(clearance outline)
				(anchor circle)
			)
			(primitives
				(gr_poly
					(pts
						(arc
							(start 0.1524 -0.127)
							(mid 0.137521 -0.162921)
							(end 0.1016 -0.1778)
						)
						(arc
							(start -0.1016 -0.1778)
							(mid -0.137521 -0.162921)
							(end -0.1524 -0.127)
						)
						(arc
							(start -0.1524 0.127)
							(mid -0.137521 0.162921)
							(end -0.1016 0.1778)
						)
						(arc
							(start 0.1016 0.1778)
							(mid 0.137521 0.162921)
							(end 0.1524 0.127)
						)
					)
					(width 0)
					(fill yes)
				)
			)
		)
		(pad "2" smd custom
			(at 0 0.2794 180)
			(size 0.0762 0.0762)
			(layers "F.Cu" "F.Mask" "F.Paste")
			(net "SAS_HDD_REDV_TX8_N")
			(options
				(clearance outline)
				(anchor circle)
			)
			(primitives
				(gr_poly
					(pts
						(arc
							(start 0.1524 -0.127)
							(mid 0.137521 -0.162921)
							(end 0.1016 -0.1778)
						)
						(arc
							(start -0.1016 -0.1778)
							(mid -0.137521 -0.162921)
							(end -0.1524 -0.127)
						)
						(arc
							(start -0.1524 0.127)
							(mid -0.137521 0.162921)
							(end -0.1016 0.1778)
						)
						(arc
							(start 0.1016 0.1778)
							(mid 0.137521 0.162921)
							(end 0.1524 0.127)
						)
					)
					(width 0)
					(fill yes)
				)
			)
		)
	)
	(footprint ""
		(layer "F.Cu")
		(at 64.77 -218.313 90)
		(property "Reference" "P2121"
			(at 0 0 90)
			(layer "F.SilkS")
			(hide yes)
			(effects
				(font
					(size 1.27 1.27)
				)
			)
		)
		(property "Value" "0R0603-PAD-2-GP-U"
			(at -0.0254 -2.2987 90)
			(unlocked yes)
			(layer "F.Fab")
			(hide yes)
			(effects
				(font
					(size 1.016 1.016)
					(thickness 0.1524)
				)
			)
		)
		(property "Device Type" "0R0603-PAD-1-U"
			(at -0.0254 -3.8227 90)
			(unlocked yes)
			(layer "F.Fab")
			(hide yes)
			(effects
				(font
					(size 1.016 1.016)
					(thickness 0.1524)
				)
			)
		)
		(duplicate_pad_numbers_are_jumpers no)
		(fp_rect
			(start -0.5842 1.3335)
			(end 0.5842 -1.3335)
			(stroke
				(width 0)
				(type default)
			)
			(fill no)
			(layer "F.CrtYd")
		)
		(fp_rect
			(start -0.5842 1.3335)
			(end 0.5842 -1.3335)
			(stroke
				(width 0)
				(type default)
			)
			(fill no)
			(layer "F.Fab")
		)
		(pad "1" smd custom
			(at 0 -0.762 90)
			(size 0.2159 0.2159)
			(layers "F.Cu" "F.Mask" "F.Paste")
			(net "AGND_CURRENT_MON")
			(options
				(clearance outline)
				(anchor circle)
			)
			(primitives
				(gr_poly
					(pts
						(arc
							(start -0.3302 -0.5842)
							(mid -0.402042 -0.554442)
							(end -0.4318 -0.4826)
						)
						(arc
							(start -0.4318 0.4826)
							(mid -0.402042 0.554442)
							(end -0.3302 0.5842)
						)
						(arc
							(start 0.3302 0.5842)
							(mid 0.402042 0.554442)
							(end 0.4318 0.4826)
						)
						(arc
							(start 0.4318 -0.4826)
							(mid 0.402042 -0.554442)
							(end 0.3302 -0.5842)
						)
					)
					(width 0)
					(fill yes)
				)
			)
		)
		(pad "2" smd custom
			(at 0 0.762 90)
			(size 0.2159 0.2159)
			(layers "F.Cu" "F.Mask" "F.Paste")
			(net "GND")
			(options
				(clearance outline)
				(anchor circle)
			)
			(primitives
				(gr_poly
					(pts
						(arc
							(start -0.4318 0.4826)
							(mid -0.402042 0.554442)
							(end -0.3302 0.5842)
						)
						(arc
							(start 0.3302 0.5842)
							(mid 0.402042 0.554442)
							(end 0.4318 0.4826)
						)
						(arc
							(start 0.4318 -0.4826)
							(mid 0.402042 -0.554442)
							(end 0.3302 -0.5842)
						)
						(arc
							(start -0.3302 -0.5842)
							(mid -0.402042 -0.554442)
							(end -0.4318 -0.4826)
						)
					)
					(width 0)
					(fill yes)
				)
			)
		)
	)
	(footprint ""
		(layer "F.Cu")
		(at 221.869 -172.212 180)
		(property "Reference" "R496"
			(at 0 0 180)
			(layer "F.SilkS")
			(hide yes)
			(effects
				(font
					(size 1.27 1.27)
				)
			)
		)
		(property "Value" "10KR2F-2-GP"
			(at 0.064008 -3.993896 180)
			(unlocked yes)
			(layer "F.Fab")
			(hide yes)
			(effects
				(font
					(size 1.016 1.016)
					(thickness 0.1524)
				)
			)
		)
		(property "Device Type" "R402H16"
			(at 0.064008 -5.517896 180)
			(unlocked yes)
			(layer "F.Fab")
			(hide yes)
			(effects
				(font
					(size 1.016 1.016)
					(thickness 0.1524)
				)
			)
		)
		(duplicate_pad_numbers_are_jumpers no)
		(fp_line
			(start 0.508 -0.9398)
			(end -0.508 -0.9398)
			(stroke
				(width 0.1524)
				(type default)
			)
			(layer "F.SilkS")
		)
		(fp_line
			(start -0.508 -0.9398)
			(end -0.508 0.9398)
			(stroke
				(width 0.1524)
				(type default)
			)
			(layer "F.SilkS")
		)
		(fp_rect
			(start -0.508 0.9398)
			(end 0.508 -0.9398)
			(stroke
				(width 0)
				(type default)
			)
			(fill no)
			(layer "F.CrtYd")
		)
		(fp_rect
			(start -0.508 0.9398)
			(end 0.508 -0.9398)
			(stroke
				(width 0)
				(type default)
			)
			(fill no)
			(layer "F.Fab")
		)
		(pad "1" smd custom
			(at 0 -0.4445 180)
			(size 0.1397 0.1397)
			(layers "F.Cu" "F.Mask" "F.Paste")
			(net "P3V3_STBY")
			(options
				(clearance outline)
				(anchor circle)
			)
			(primitives
				(gr_poly
					(pts
						(arc
							(start -0.1778 -0.2794)
							(mid -0.249642 -0.249642)
							(end -0.2794 -0.1778)
						)
						(arc
							(start -0.2794 0.1778)
							(mid -0.249642 0.249642)
							(end -0.1778 0.2794)
						)
						(arc
							(start 0.1778 0.2794)
							(mid 0.249642 0.249642)
							(end 0.2794 0.1778)
						)
						(arc
							(start 0.2794 -0.1778)
							(mid 0.249642 -0.249642)
							(end 0.1778 -0.2794)
						)
					)
					(width 0)
					(fill yes)
				)
			)
		)
		(pad "2" smd custom
			(at 0 0.4445 180)
			(size 0.1397 0.1397)
			(layers "F.Cu" "F.Mask" "F.Paste")
			(net "INVERTER_G2_EXP")
			(options
				(clearance outline)
				(anchor circle)
			)
			(primitives
				(gr_poly
					(pts
						(arc
							(start -0.1778 -0.2794)
							(mid -0.249642 -0.249642)
							(end -0.2794 -0.1778)
						)
						(arc
							(start -0.2794 0.1778)
							(mid -0.249642 0.249642)
							(end -0.1778 0.2794)
						)
						(arc
							(start 0.1778 0.2794)
							(mid 0.249642 0.249642)
							(end 0.2794 0.1778)
						)
						(arc
							(start 0.2794 -0.1778)
							(mid 0.249642 -0.249642)
							(end 0.1778 -0.2794)
						)
					)
					(width 0)
					(fill yes)
				)
			)
		)
	)
)
